# T6G (Grand Teton) — schematic netlist excerpt (pin names and nets, part order shuffled) for the footprints in the layout excerpt that follows; sources: Cadence DE-HDL packaged netlist, KiCad conversion of 04192023_DAF0TMB3IC0_F0TG_MB_C_brd_V02_OCP.brd

C469  Q_CAP  4.7UF 6.3V 20% X6S  pkg 0402  page 356 : A = P0V9_CPU1_RT3_2A ; B = GND
PC6509  Q_CAP  22UF 4V 20% X6S  pkg C0805  page 360 : A = P1V8_CPU0_RT_1D ; B = GND
C2393  Q_CAP  22UF 4V 20% X6S  pkg C0402  page 73 : A = PVDDCR_CPU1_P1 ; B = GND

(kicad_pcb
	(version 20260206)
	(generator "pcbnew")
	(generator_version "10.0")
	(general
		(thickness 1.6)
		(legacy_teardrops no)
	)
	(paper "A4")
	(title_block
		(title "04192023_DAF0TMB3IC0_F0TG_MB_C_brd_V02_OCP.brd")
		(comment 1 "Grand Teton / footprints 5809-5811 of 8354")
	)
	(layers
		(0 "F.Cu" signal "TOP")
		(4 "In1.Cu" signal "GND")
		(6 "In2.Cu" signal "IN1")
		(8 "In3.Cu" signal "GND1")
		(10 "In4.Cu" signal "IN2")
		(12 "In5.Cu" signal "GND2")
		(14 "In6.Cu" signal "IN3")
		(16 "In7.Cu" signal "GND3")
		(18 "In8.Cu" signal "VCC")
		(20 "In9.Cu" signal "VCC1")
		(22 "In10.Cu" signal "GND4")
		(24 "In11.Cu" signal "IN4")
		(26 "In12.Cu" signal "GND5")
		(28 "In13.Cu" signal "IN5")
		(30 "In14.Cu" signal "GND6")
		(32 "In15.Cu" signal "IN6")
		(34 "In16.Cu" signal "GND7")
		(2 "B.Cu" signal "BOTTOM")
		(9 "F.Adhes" user "F.Adhesive")
		(11 "B.Adhes" user "B.Adhesive")
		(13 "F.Paste" user "Package Geometry/Pastemask Top")
		(15 "B.Paste" user "Package Geometry/Pastemask Bottom")
		(5 "F.SilkS" user "Ref Des/Silkscreen Top")
		(7 "B.SilkS" user "Ref Des/Silkscreen Bottom")
		(1 "F.Mask" user "Board Geometry/Soldermask Top")
		(3 "B.Mask" user "Board Geometry/Soldermask Bottom")
		(17 "Dwgs.User" user "User.Drawings")
		(19 "Cmts.User" user "User.Comments")
		(21 "Eco1.User" user "User.Eco1")
		(23 "Eco2.User" user "User.Eco2")
		(25 "Edge.Cuts" user "Board Geometry/Outline")
		(27 "Margin" user)
		(31 "F.CrtYd" user "Package Geometry/Place Bound Top")
		(29 "B.CrtYd" user "Package Geometry/Place Bound Bottom")
		(35 "F.Fab" user "Ref Des/Assembly Top")
		(33 "B.Fab" user "Ref Des/Assembly Bottom")
	)
	(footprint ""
		(layer "B.Cu")
		(at 247.651778 -315.95568 -90)
		(property "Reference" "PC6509"
			(at 0 0 90)
			(layer "B.SilkS")
			(hide yes)
			(effects
				(font
					(size 1.27 1.27)
				)
				(justify mirror)
			)
		)
		(property "Value" ""
			(at 0 0 90)
			(layer "B.Fab")
			(effects
				(font
					(size 1.27 1.27)
				)
				(justify mirror)
			)
		)
		(duplicate_pad_numbers_are_jumpers no)
		(fp_line
			(start -1.524 0.762)
			(end 1.524 0.762)
			(stroke
				(width 0.1524)
				(type default)
			)
			(layer "B.SilkS")
		)
		(fp_line
			(start 1.524 0.762)
			(end 1.524 -0.762)
			(stroke
				(width 0.1524)
				(type default)
			)
			(layer "B.SilkS")
		)
		(fp_line
			(start -1.524 -0.762)
			(end -1.524 0.762)
			(stroke
				(width 0.1524)
				(type default)
			)
			(layer "B.SilkS")
		)
		(fp_line
			(start 1.524 -0.762)
			(end -1.524 -0.762)
			(stroke
				(width 0.1524)
				(type default)
			)
			(layer "B.SilkS")
		)
		(fp_line
			(start -1.1049 0.724916)
			(end -1.1049 -0.724916)
			(stroke
				(width 0.1)
				(type default)
			)
			(layer "B.Fab")
		)
		(fp_line
			(start 1.1049 0.724916)
			(end -1.1049 0.724916)
			(stroke
				(width 0.1)
				(type default)
			)
			(layer "B.Fab")
		)
		(fp_line
			(start -1.1049 -0.724916)
			(end 1.1049 -0.724916)
			(stroke
				(width 0.1)
				(type default)
			)
			(layer "B.Fab")
		)
		(fp_line
			(start 1.1049 -0.724916)
			(end 1.1049 0.724916)
			(stroke
				(width 0.1)
				(type default)
			)
			(layer "B.Fab")
		)
		(pad "1" smd rect
			(at 0.889 0 270)
			(size 1.016 1.27)
			(layers "B.Cu" "B.Mask" "B.Paste")
			(net "P1V8_CPU0_RT_1D")
		)
		(pad "2" smd rect
			(at -0.889 0 270)
			(size 1.016 1.27)
			(layers "B.Cu" "B.Mask" "B.Paste")
			(net "GND")
		)
	)
	(footprint ""
		(layer "B.Cu")
		(at 102.783386 -269.307564)
		(property "Reference" "C2393"
			(at 0 0 0)
			(layer "B.SilkS")
			(hide yes)
			(effects
				(font
					(size 1.27 1.27)
				)
				(justify mirror)
			)
		)
		(property "Value" ""
			(at 0 0 0)
			(layer "B.Fab")
			(effects
				(font
					(size 1.27 1.27)
				)
				(justify mirror)
			)
		)
		(duplicate_pad_numbers_are_jumpers no)
		(fp_line
			(start -0.7874 -0.4064)
			(end -0.7874 0.4064)
			(stroke
				(width 0.1524)
				(type default)
			)
			(layer "B.SilkS")
		)
		(fp_line
			(start -0.7874 0.4064)
			(end 0.7874 0.4064)
			(stroke
				(width 0.1524)
				(type default)
			)
			(layer "B.SilkS")
		)
		(fp_line
			(start 0.7874 -0.4064)
			(end -0.7874 -0.4064)
			(stroke
				(width 0.1524)
				(type default)
			)
			(layer "B.SilkS")
		)
		(fp_line
			(start 0.7874 0.4064)
			(end 0.7874 -0.4064)
			(stroke
				(width 0.1524)
				(type default)
			)
			(layer "B.SilkS")
		)
		(fp_line
			(start -0.67945 -0.3048)
			(end -0.67945 0.3048)
			(stroke
				(width 0.1)
				(type default)
			)
			(layer "B.Fab")
		)
		(fp_line
			(start -0.67945 0.3048)
			(end -0.120396 0.3048)
			(stroke
				(width 0.1)
				(type default)
			)
			(layer "B.Fab")
		)
		(fp_line
			(start -0.12065 -0.3048)
			(end -0.67945 -0.3048)
			(stroke
				(width 0.1)
				(type default)
			)
			(layer "B.Fab")
		)
		(fp_line
			(start -0.12065 -0.2794)
			(end -0.12065 -0.3048)
			(stroke
				(width 0.1)
				(type default)
			)
			(layer "B.Fab")
		)
		(fp_line
			(start -0.120396 0.2794)
			(end 0.12065 0.2794)
			(stroke
				(width 0.1)
				(type default)
			)
			(layer "B.Fab")
		)
		(fp_line
			(start -0.120396 0.3048)
			(end -0.120396 0.2794)
			(stroke
				(width 0.1)
				(type default)
			)
			(layer "B.Fab")
		)
		(fp_line
			(start 0.12065 -0.305054)
			(end 0.12065 -0.2794)
			(stroke
				(width 0.1)
				(type default)
			)
			(layer "B.Fab")
		)
		(fp_line
			(start 0.12065 -0.2794)
			(end -0.12065 -0.2794)
			(stroke
				(width 0.1)
				(type default)
			)
			(layer "B.Fab")
		)
		(fp_line
			(start 0.12065 0.2794)
			(end 0.12065 0.3048)
			(stroke
				(width 0.1)
				(type default)
			)
			(layer "B.Fab")
		)
		(fp_line
			(start 0.12065 0.3048)
			(end 0.67945 0.3048)
			(stroke
				(width 0.1)
				(type default)
			)
			(layer "B.Fab")
		)
		(fp_line
			(start 0.67945 -0.305054)
			(end 0.12065 -0.305054)
			(stroke
				(width 0.1)
				(type default)
			)
			(layer "B.Fab")
		)
		(fp_line
			(start 0.67945 0.3048)
			(end 0.67945 -0.305054)
			(stroke
				(width 0.1)
				(type default)
			)
			(layer "B.Fab")
		)
		(pad "1" smd circle
			(at 0.40005 0 180)
			(size 0 0)
			(layers "B.Cu" "B.Mask" "B.Paste")
			(net "PVDDCR_CPU1_P1")
		)
		(pad "2" smd circle
			(at -0.40005 0 180)
			(size 0 0)
			(layers "B.Cu" "B.Mask" "B.Paste")
			(net "GND")
		)
	)
	(footprint ""
		(layer "B.Cu")
		(at 113.587276 -391.340848 -90)
		(property "Reference" "C469"
			(at 0 0 90)
			(layer "B.SilkS")
			(hide yes)
			(effects
				(font
					(size 1.27 1.27)
				)
				(justify mirror)
			)
		)
		(property "Value" ""
			(at 0 0 90)
			(layer "B.Fab")
			(effects
				(font
					(size 1.27 1.27)
				)
				(justify mirror)
			)
		)
		(duplicate_pad_numbers_are_jumpers no)
		(fp_line
			(start -0.7874 0.4064)
			(end 0.7874 0.4064)
			(stroke
				(width 0.1524)
				(type default)
			)
			(layer "B.SilkS")
		)
		(fp_line
			(start 0.7874 0.4064)
			(end 0.7874 -0.4064)
			(stroke
				(width 0.1524)
				(type default)
			)
			(layer "B.SilkS")
		)
		(fp_line
			(start -0.7874 -0.4064)
			(end -0.7874 0.4064)
			(stroke
				(width 0.1524)
				(type default)
			)
			(layer "B.SilkS")
		)
		(fp_line
			(start 0.7874 -0.4064)
			(end -0.7874 -0.4064)
			(stroke
				(width 0.1524)
				(type default)
			)
			(layer "B.SilkS")
		)
		(fp_line
			(start -0.67945 0.3048)
			(end -0.120396 0.3048)
			(stroke
				(width 0.1)
				(type default)
			)
			(layer "B.Fab")
		)
		(fp_line
			(start -0.120396 0.3048)
			(end -0.120396 0.2794)
			(stroke
				(width 0.1)
				(type default)
			)
			(layer "B.Fab")
		)
		(fp_line
			(start 0.12065 0.3048)
			(end 0.67945 0.3048)
			(stroke
				(width 0.1)
				(type default)
			)
			(layer "B.Fab")
		)
		(fp_line
			(start 0.67945 0.3048)
			(end 0.67945 -0.305054)
			(stroke
				(width 0.1)
				(type default)
			)
			(layer "B.Fab")
		)
		(fp_line
			(start -0.120396 0.2794)
			(end 0.12065 0.2794)
			(stroke
				(width 0.1)
				(type default)
			)
			(layer "B.Fab")
		)
		(fp_line
			(start 0.12065 0.2794)
			(end 0.12065 0.3048)
			(stroke
				(width 0.1)
				(type default)
			)
			(layer "B.Fab")
		)
		(fp_line
			(start -0.12065 -0.2794)
			(end -0.12065 -0.3048)
			(stroke
				(width 0.1)
				(type default)
			)
			(layer "B.Fab")
		)
		(fp_line
			(start 0.12065 -0.2794)
			(end -0.12065 -0.2794)
			(stroke
				(width 0.1)
				(type default)
			)
			(layer "B.Fab")
		)
		(fp_line
			(start -0.67945 -0.3048)
			(end -0.67945 0.3048)
			(stroke
				(width 0.1)
				(type default)
			)
			(layer "B.Fab")
		)
		(fp_line
			(start -0.12065 -0.3048)
			(end -0.67945 -0.3048)
			(stroke
				(width 0.1)
				(type default)
			)
			(layer "B.Fab")
		)
		(fp_line
			(start 0.12065 -0.305054)
			(end 0.12065 -0.2794)
			(stroke
				(width 0.1)
				(type default)
			)
			(layer "B.Fab")
		)
		(fp_line
			(start 0.67945 -0.305054)
			(end 0.12065 -0.305054)
			(stroke
				(width 0.1)
				(type default)
			)
			(layer "B.Fab")
		)
		(pad "1" smd circle
			(at 0.40005 0 90)
			(size 0 0)
			(layers "B.Cu" "B.Mask" "B.Paste")
			(net "P0V9_CPU1_RT3_2A")
		)
		(pad "2" smd circle
			(at -0.40005 0 90)
			(size 0 0)
			(layers "B.Cu" "B.Mask" "B.Paste")
			(net "GND")
		)
	)
)
